(kicad_pcb
	(version 20260206)
	(generator "pcbnew")
	(generator_version "10.0")
	(general
		(thickness 1.6)
		(legacy_teardrops no)
	)
	(paper "A4")
	(title_block
		(title "Bryce Canyon_IOM_M2_16342-2_OCP.brd")
		(comment 1 "Bryce Canyon / footprints 290-298 of 1146")
	)
	(layers
		(0 "F.Cu" signal "TOP")
		(4 "In1.Cu" signal "L2GND")
		(6 "In2.Cu" signal "L3")
		(8 "In3.Cu" signal "L4VCC")
		(10 "In4.Cu" signal "L5VCC")
		(12 "In5.Cu" signal "L6")
		(14 "In6.Cu" signal "L7GND")
		(2 "B.Cu" signal "BOTTOM")
		(9 "F.Adhes" user "F.Adhesive")
		(11 "B.Adhes" user "B.Adhesive")
		(13 "F.Paste" user "Package Geometry/Pastemask Top")
		(15 "B.Paste" user "Package Geometry/Pastemask Bottom")
		(5 "F.SilkS" user "Ref Des/Silkscreen Top")
		(7 "B.SilkS" user "Ref Des/Silkscreen Bottom")
		(1 "F.Mask" user "Board Geometry/Soldermask Top")
		(3 "B.Mask" user "Board Geometry/Soldermask Bottom")
		(17 "Dwgs.User" user "User.Drawings")
		(19 "Cmts.User" user "User.Comments")
		(21 "Eco1.User" user "User.Eco1")
		(23 "Eco2.User" user "User.Eco2")
		(25 "Edge.Cuts" user "Board Geometry/Outline")
		(27 "Margin" user)
		(31 "F.CrtYd" user "Package Geometry/Place Bound Top")
		(29 "B.CrtYd" user "Package Geometry/Place Bound Bottom")
		(35 "F.Fab" user "Ref Des/Assembly Top")
		(33 "B.Fab" user "Ref Des/Assembly Bottom")
	)
	(footprint ""
		(layer "F.Cu")
		(at 41.123108 -131.482846 180)
		(property "Reference" "R376"
			(at 0 0 180)
			(layer "F.SilkS")
			(hide yes)
			(effects
				(font
					(size 1.27 1.27)
				)
			)
		)
		(property "Value" "4K7R2F-GP"
			(at 0.064008 -3.993896 180)
			(unlocked yes)
			(layer "F.Fab")
			(hide yes)
			(effects
				(font
					(size 1.016 1.016)
					(thickness 0.1524)
				)
			)
		)
		(property "Device Type" "R402H16"
			(at 0.064008 -5.517896 180)
			(unlocked yes)
			(layer "F.Fab")
			(hide yes)
			(effects
				(font
					(size 1.016 1.016)
					(thickness 0.1524)
				)
			)
		)
		(duplicate_pad_numbers_are_jumpers no)
		(fp_line
			(start 0.508 -0.9398)
			(end -0.508 -0.9398)
			(stroke
				(width 0.1524)
				(type default)
			)
			(layer "F.SilkS")
		)
		(fp_line
			(start -0.508 -0.9398)
			(end -0.508 0.9398)
			(stroke
				(width 0.1524)
				(type default)
			)
			(layer "F.SilkS")
		)
		(fp_rect
			(start -0.508 0.9398)
			(end 0.508 -0.9398)
			(stroke
				(width 0)
				(type default)
			)
			(fill no)
			(layer "F.CrtYd")
		)
		(fp_rect
			(start -0.508 0.9398)
			(end 0.508 -0.9398)
			(stroke
				(width 0)
				(type default)
			)
			(fill no)
			(layer "F.Fab")
		)
		(pad "1" smd custom
			(at 0 -0.4445 180)
			(size 0.1397 0.1397)
			(layers "F.Cu" "F.Mask" "F.Paste")
			(net "P3V3_STBY")
			(options
				(clearance outline)
				(anchor circle)
			)
			(primitives
				(gr_poly
					(pts
						(arc
							(start -0.1778 -0.2794)
							(mid -0.249642 -0.249642)
							(end -0.2794 -0.1778)
						)
						(arc
							(start -0.2794 0.1778)
							(mid -0.249642 0.249642)
							(end -0.1778 0.2794)
						)
						(arc
							(start 0.1778 0.2794)
							(mid 0.249642 0.249642)
							(end 0.2794 0.1778)
						)
						(arc
							(start 0.2794 -0.1778)
							(mid 0.249642 -0.249642)
							(end 0.1778 -0.2794)
						)
					)
					(width 0)
					(fill yes)
				)
			)
		)
		(pad "2" smd custom
			(at 0 0.4445 180)
			(size 0.1397 0.1397)
			(layers "F.Cu" "F.Mask" "F.Paste")
			(net "BMC_GPIOZ4")
			(options
				(clearance outline)
				(anchor circle)
			)
			(primitives
				(gr_poly
					(pts
						(arc
							(start -0.1778 -0.2794)
							(mid -0.249642 -0.249642)
							(end -0.2794 -0.1778)
						)
						(arc
							(start -0.2794 0.1778)
							(mid -0.249642 0.249642)
							(end -0.1778 0.2794)
						)
						(arc
							(start 0.1778 0.2794)
							(mid 0.249642 0.249642)
							(end 0.2794 0.1778)
						)
						(arc
							(start 0.2794 -0.1778)
							(mid 0.249642 -0.249642)
							(end 0.1778 -0.2794)
						)
					)
					(width 0)
					(fill yes)
				)
			)
		)
	)
	(footprint ""
		(layer "F.Cu")
		(at 62.947296 -159.921956 90)
		(property "Reference" "C95"
			(at 0 0 90)
			(layer "F.SilkS")
			(hide yes)
			(effects
				(font
					(size 1.27 1.27)
				)
			)
		)
		(property "Value" "SC1U16V3KX-5GP"
			(at 0 -2.8194 90)
			(unlocked yes)
			(layer "F.Fab")
			(hide yes)
			(effects
				(font
					(size 1.016 1.016)
					(thickness 0.1524)
				)
			)
		)
		(property "Device Type" "C603H36"
			(at 0 -4.3434 90)
			(unlocked yes)
			(layer "F.Fab")
			(hide yes)
			(effects
				(font
					(size 1.016 1.016)
					(thickness 0.1524)
				)
			)
		)
		(duplicate_pad_numbers_are_jumpers no)
		(fp_line
			(start 0.508 0)
			(end -0.508 0)
			(stroke
				(width 0.2032)
				(type default)
			)
			(layer "F.SilkS")
		)
		(fp_rect
			(start -0.5842 1.3335)
			(end 0.5842 -1.3335)
			(stroke
				(width 0)
				(type default)
			)
			(fill no)
			(layer "F.CrtYd")
		)
		(fp_rect
			(start -0.5842 1.3335)
			(end 0.5842 -1.3335)
			(stroke
				(width 0)
				(type default)
			)
			(fill no)
			(layer "F.Fab")
		)
		(pad "1" smd custom
			(at 0 -0.762 90)
			(size 0.2159 0.2159)
			(layers "F.Cu" "F.Mask" "F.Paste")
			(net "VPLLAV33")
			(options
				(clearance outline)
				(anchor circle)
			)
			(primitives
				(gr_poly
					(pts
						(arc
							(start -0.3302 -0.4318)
							(mid -0.402042 -0.402042)
							(end -0.4318 -0.3302)
						)
						(arc
							(start -0.4318 0.3302)
							(mid -0.402042 0.402042)
							(end -0.3302 0.4318)
						)
						(arc
							(start 0.3302 0.4318)
							(mid 0.402042 0.402042)
							(end 0.4318 0.3302)
						)
						(arc
							(start 0.4318 -0.3302)
							(mid 0.402042 -0.402042)
							(end 0.3302 -0.4318)
						)
					)
					(width 0)
					(fill yes)
				)
			)
		)
		(pad "2" smd custom
			(at 0 0.762 90)
			(size 0.2159 0.2159)
			(layers "F.Cu" "F.Mask" "F.Paste")
			(net "GND")
			(options
				(clearance outline)
				(anchor circle)
			)
			(primitives
				(gr_poly
					(pts
						(arc
							(start -0.3302 -0.4318)
							(mid -0.402042 -0.402042)
							(end -0.4318 -0.3302)
						)
						(arc
							(start -0.4318 0.3302)
							(mid -0.402042 0.402042)
							(end -0.3302 0.4318)
						)
						(arc
							(start 0.3302 0.4318)
							(mid 0.402042 0.402042)
							(end 0.4318 0.3302)
						)
						(arc
							(start 0.4318 -0.3302)
							(mid 0.402042 -0.402042)
							(end 0.3302 -0.4318)
						)
					)
					(width 0)
					(fill yes)
				)
			)
		)
	)
	(footprint ""
		(layer "F.Cu")
		(at 77.1398 -156.561536 -90)
		(property "Reference" "R537"
			(at 0 0 270)
			(layer "F.SilkS")
			(hide yes)
			(effects
				(font
					(size 1.27 1.27)
				)
			)
		)
		(property "Value" "2K05R2F-1-GP"
			(at 0.064008 -3.993896 270)
			(unlocked yes)
			(layer "F.Fab")
			(hide yes)
			(effects
				(font
					(size 1.016 1.016)
					(thickness 0.1524)
				)
			)
		)
		(property "Device Type" "R402H16"
			(at 0.064008 -5.517896 270)
			(unlocked yes)
			(layer "F.Fab")
			(hide yes)
			(effects
				(font
					(size 1.016 1.016)
					(thickness 0.1524)
				)
			)
		)
		(duplicate_pad_numbers_are_jumpers no)
		(fp_line
			(start -0.508 -0.9398)
			(end -0.508 0.9398)
			(stroke
				(width 0.1524)
				(type default)
			)
			(layer "F.SilkS")
		)
		(fp_line
			(start 0.508 -0.9398)
			(end -0.508 -0.9398)
			(stroke
				(width 0.1524)
				(type default)
			)
			(layer "F.SilkS")
		)
		(fp_rect
			(start -0.508 0.9398)
			(end 0.508 -0.9398)
			(stroke
				(width 0)
				(type default)
			)
			(fill no)
			(layer "F.CrtYd")
		)
		(fp_rect
			(start -0.508 0.9398)
			(end 0.508 -0.9398)
			(stroke
				(width 0)
				(type default)
			)
			(fill no)
			(layer "F.Fab")
		)
		(pad "1" smd custom
			(at 0 -0.4445 270)
			(size 0.1397 0.1397)
			(layers "F.Cu" "F.Mask" "F.Paste")
			(net "TPS74801_P1V15_STBY_OUT")
			(options
				(clearance outline)
				(anchor circle)
			)
			(primitives
				(gr_poly
					(pts
						(arc
							(start -0.1778 -0.2794)
							(mid -0.249642 -0.249642)
							(end -0.2794 -0.1778)
						)
						(arc
							(start -0.2794 0.1778)
							(mid -0.249642 0.249642)
							(end -0.1778 0.2794)
						)
						(arc
							(start 0.1778 0.2794)
							(mid 0.249642 0.249642)
							(end 0.2794 0.1778)
						)
						(arc
							(start 0.2794 -0.1778)
							(mid 0.249642 -0.249642)
							(end 0.1778 -0.2794)
						)
					)
					(width 0)
					(fill yes)
				)
			)
		)
		(pad "2" smd custom
			(at 0 0.4445 270)
			(size 0.1397 0.1397)
			(layers "F.Cu" "F.Mask" "F.Paste")
			(net "TPS74801_P1V15_STBY_FB")
			(options
				(clearance outline)
				(anchor circle)
			)
			(primitives
				(gr_poly
					(pts
						(arc
							(start -0.1778 -0.2794)
							(mid -0.249642 -0.249642)
							(end -0.2794 -0.1778)
						)
						(arc
							(start -0.2794 0.1778)
							(mid -0.249642 0.249642)
							(end -0.1778 0.2794)
						)
						(arc
							(start 0.1778 0.2794)
							(mid 0.249642 0.249642)
							(end 0.2794 0.1778)
						)
						(arc
							(start 0.2794 -0.1778)
							(mid 0.249642 -0.249642)
							(end 0.1778 -0.2794)
						)
					)
					(width 0)
					(fill yes)
				)
			)
		)
	)
	(footprint ""
		(layer "F.Cu")
		(at 156.729938 -17.603978 90)
		(property "Reference" "C205"
			(at 0 0 90)
			(layer "F.SilkS")
			(hide yes)
			(effects
				(font
					(size 1.27 1.27)
				)
			)
		)
		(property "Value" "SC10U16V5KX-7-GP-U"
			(at -0.0762 -6.1214 90)
			(unlocked yes)
			(layer "F.Fab")
			(hide yes)
			(effects
				(font
					(size 1.016 1.016)
					(thickness 0.1524)
				)
			)
		)
		(property "Device Type" "C805H58"
			(at -0.0762 -8.1534 90)
			(unlocked yes)
			(layer "F.Fab")
			(hide yes)
			(effects
				(font
					(size 1.016 1.016)
					(thickness 0.1524)
				)
			)
		)
		(duplicate_pad_numbers_are_jumpers no)
		(fp_line
			(start 0.635 0)
			(end -0.635 0)
			(stroke
				(width 0.508)
				(type default)
			)
			(layer "F.SilkS")
		)
		(fp_rect
			(start -0.9652 1.778)
			(end 0.9652 -1.778)
			(stroke
				(width 0)
				(type default)
			)
			(fill no)
			(layer "F.CrtYd")
		)
		(fp_poly
			(pts
				(xy -0.9652 -1.778) (xy 0.9652 -1.778) (xy 0.9652 1.778) (xy -0.9652 1.778)
			)
			(stroke
				(width 0)
				(type default)
			)
			(fill no)
			(layer "F.Fab")
		)
		(pad "1" smd rect
			(at 0 -0.9652 90)
			(size 1.397 1.143)
			(layers "F.Cu" "F.Mask" "F.Paste")
			(net "P12V_STBY_VIN_PU4")
		)
		(pad "2" smd rect
			(at 0 0.9652 90)
			(size 1.397 1.143)
			(layers "F.Cu" "F.Mask" "F.Paste")
			(net "GND")
		)
	)
	(footprint ""
		(layer "F.Cu")
		(at 77.283818 -74.153268 90)
		(property "Reference" "VIA2"
			(at 0 0 90)
			(layer "F.SilkS")
			(hide yes)
			(effects
				(font
					(size 1.27 1.27)
				)
			)
		)
		(property "Value" "85OHM-8L-1D6MM-L16L18-GP"
			(at 4.064 0.6096 90)
			(unlocked yes)
			(layer "F.Fab")
			(hide yes)
			(effects
				(font
					(size 1.016 1.016)
					(thickness 0.1524)
				)
			)
		)
		(property "Device Type" "VIA-PCIE-4P-368076"
			(at 4.064 -0.9144 90)
			(unlocked yes)
			(layer "F.Fab")
			(hide yes)
			(effects
				(font
					(size 1.016 1.016)
					(thickness 0.1524)
				)
			)
		)
		(duplicate_pad_numbers_are_jumpers no)
		(fp_rect
			(start -1.8415 0.381)
			(end 1.8415 -0.381)
			(stroke
				(width 0)
				(type default)
			)
			(fill no)
			(layer "F.CrtYd")
		)
		(fp_rect
			(start -1.8415 0.381)
			(end 1.8415 -0.381)
			(stroke
				(width 0)
				(type default)
			)
			(fill no)
			(layer "F.Fab")
		)
		(pad "1" thru_hole circle
			(at -1.4605 0 90)
			(size 0.508 0.508)
			(drill 0.254)
			(layers "*.Cu" "*.Mask")
			(remove_unused_layers no)
			(net "GND")
			(clearance 0.127)
			(thermal_gap 0.127)
		)
		(pad "2" thru_hole circle
			(at -0.4445 0 90)
			(size 0.508 0.508)
			(drill 0.254)
			(layers "*.Cu" "*.Mask")
			(remove_unused_layers no)
			(net "PCIE_COMP_TO_IOM_17_DP")
			(clearance 0.127)
			(thermal_gap 0.127)
		)
		(pad "3" thru_hole circle
			(at 0.4445 0 90)
			(size 0.508 0.508)
			(drill 0.254)
			(layers "*.Cu" "*.Mask")
			(remove_unused_layers no)
			(net "PCIE_COMP_TO_IOM_17_DN")
			(clearance 0.127)
			(thermal_gap 0.127)
		)
		(pad "4" thru_hole circle
			(at 1.4605 0 90)
			(size 0.508 0.508)
			(drill 0.254)
			(layers "*.Cu" "*.Mask")
			(remove_unused_layers no)
			(net "GND")
			(clearance 0.127)
			(thermal_gap 0.127)
		)
	)
	(footprint ""
		(layer "F.Cu")
		(at 23.2918 -183.5658 90)
		(property "Reference" "L8"
			(at 0 0 90)
			(layer "F.SilkS")
			(hide yes)
			(effects
				(font
					(size 1.27 1.27)
				)
			)
		)
		(property "Value" "BLM21PG220SN1DGP"
			(at 0.0254 -5.6896 90)
			(unlocked yes)
			(layer "F.Fab")
			(hide yes)
			(effects
				(font
					(size 1.016 1.016)
					(thickness 0.1524)
				)
			)
		)
		(property "Device Type" "L20125H42"
			(at 0.0254 -7.5946 90)
			(unlocked yes)
			(layer "F.Fab")
			(hide yes)
			(effects
				(font
					(size 1.016 1.016)
					(thickness 0.1524)
				)
			)
		)
		(duplicate_pad_numbers_are_jumpers no)
		(fp_line
			(start 0.9144 -1.7018)
			(end -0.9144 -1.7018)
			(stroke
				(width 0.1524)
				(type default)
			)
			(layer "F.SilkS")
		)
		(fp_line
			(start -0.9144 -1.7018)
			(end -0.9144 1.7018)
			(stroke
				(width 0.1524)
				(type default)
			)
			(layer "F.SilkS")
		)
		(fp_line
			(start 0.9144 1.7018)
			(end 0.9144 -1.7018)
			(stroke
				(width 0.1524)
				(type default)
			)
			(layer "F.SilkS")
		)
		(fp_line
			(start -0.9144 1.7018)
			(end 0.9144 1.7018)
			(stroke
				(width 0.1524)
				(type default)
			)
			(layer "F.SilkS")
		)
		(fp_rect
			(start -1.0033 1.778)
			(end 1.0033 -1.778)
			(stroke
				(width 0)
				(type default)
			)
			(fill no)
			(layer "F.CrtYd")
		)
		(fp_poly
			(pts
				(xy -1.0033 -1.778) (xy 1.0033 -1.778) (xy 1.0033 1.778) (xy -1.0033 1.778)
			)
			(stroke
				(width 0)
				(type default)
			)
			(fill no)
			(layer "F.Fab")
		)
		(pad "1" smd rect
			(at 0 -0.9652 90)
			(size 1.397 1.143)
			(layers "F.Cu" "F.Mask" "F.Paste")
			(net "P12V_STBY")
		)
		(pad "2" smd rect
			(at 0 0.9652 90)
			(size 1.397 1.143)
			(layers "F.Cu" "F.Mask" "F.Paste")
			(net "P12V_STBY_VIN_PU2")
		)
	)
	(footprint ""
		(layer "F.Cu")
		(at 60.44692 -141.149578)
		(property "Reference" "TP55"
			(at 0 0 0)
			(layer "F.SilkS")
			(hide yes)
			(effects
				(font
					(size 1.27 1.27)
				)
			)
		)
		(property "Value" "TPAD28-2-GP"
			(at -0.0127 -1.6637 0)
			(unlocked yes)
			(layer "F.Fab")
			(hide yes)
			(effects
				(font
					(size 1.016 1.016)
					(thickness 0.1524)
				)
			)
		)
		(property "Device Type" "TPAD28"
			(at -0.0127 -3.1877 0)
			(unlocked yes)
			(layer "F.Fab")
			(hide yes)
			(effects
				(font
					(size 1.016 1.016)
					(thickness 0.1524)
				)
			)
		)
		(duplicate_pad_numbers_are_jumpers no)
		(fp_poly
			(pts
				(arc
					(start 0.3556 0)
					(mid -0.3556 0)
					(end 0.3556 0)
				)
			)
			(stroke
				(width 0)
				(type default)
			)
			(fill no)
			(layer "F.CrtYd")
		)
		(fp_poly
			(pts
				(arc
					(start 0.6096 0)
					(mid -0.6096 0)
					(end 0.6096 0)
				)
			)
			(stroke
				(width 0)
				(type default)
			)
			(fill no)
			(layer "F.Fab")
		)
		(pad "1" smd circle
			(at 0 0)
			(size 0.7112 0.7112)
			(layers "F.Cu" "F.Mask" "F.Paste")
			(net "TP_BMC_GPIOA7")
		)
	)
	(footprint ""
		(layer "F.Cu")
		(at 149.948138 -14.987778)
		(property "Reference" "R515"
			(at 0 0 0)
			(layer "F.SilkS")
			(hide yes)
			(effects
				(font
					(size 1.27 1.27)
				)
			)
		)
		(property "Value" "13K7R2F-GP"
			(at 0.064008 -3.993896 0)
			(unlocked yes)
			(layer "F.Fab")
			(hide yes)
			(effects
				(font
					(size 1.016 1.016)
					(thickness 0.1524)
				)
			)
		)
		(property "Device Type" "R402H16"
			(at 0.064008 -5.517896 0)
			(unlocked yes)
			(layer "F.Fab")
			(hide yes)
			(effects
				(font
					(size 1.016 1.016)
					(thickness 0.1524)
				)
			)
		)
		(duplicate_pad_numbers_are_jumpers no)
		(fp_line
			(start -0.508 -0.9398)
			(end -0.508 0.9398)
			(stroke
				(width 0.1524)
				(type default)
			)
			(layer "F.SilkS")
		)
		(fp_line
			(start 0.508 -0.9398)
			(end -0.508 -0.9398)
			(stroke
				(width 0.1524)
				(type default)
			)
			(layer "F.SilkS")
		)
		(fp_rect
			(start -0.508 0.9398)
			(end 0.508 -0.9398)
			(stroke
				(width 0)
				(type default)
			)
			(fill no)
			(layer "F.CrtYd")
		)
		(fp_rect
			(start -0.508 0.9398)
			(end 0.508 -0.9398)
			(stroke
				(width 0)
				(type default)
			)
			(fill no)
			(layer "F.Fab")
		)
		(pad "1" smd custom
			(at 0 -0.4445)
			(size 0.1397 0.1397)
			(layers "F.Cu" "F.Mask" "F.Paste")
			(net "P1V8_STBY_CC_R")
			(options
				(clearance outline)
				(anchor circle)
			)
			(primitives
				(gr_poly
					(pts
						(arc
							(start -0.1778 -0.2794)
							(mid -0.249642 -0.249642)
							(end -0.2794 -0.1778)
						)
						(arc
							(start -0.2794 0.1778)
							(mid -0.249642 0.249642)
							(end -0.1778 0.2794)
						)
						(arc
							(start 0.1778 0.2794)
							(mid 0.249642 0.249642)
							(end 0.2794 0.1778)
						)
						(arc
							(start 0.2794 -0.1778)
							(mid 0.249642 -0.249642)
							(end 0.1778 -0.2794)
						)
					)
					(width 0)
					(fill yes)
				)
			)
		)
		(pad "2" smd custom
			(at 0 0.4445)
			(size 0.1397 0.1397)
			(layers "F.Cu" "F.Mask" "F.Paste")
			(net "P1V8_STBY_VFB")
			(options
				(clearance outline)
				(anchor circle)
			)
			(primitives
				(gr_poly
					(pts
						(arc
							(start -0.1778 -0.2794)
							(mid -0.249642 -0.249642)
							(end -0.2794 -0.1778)
						)
						(arc
							(start -0.2794 0.1778)
							(mid -0.249642 0.249642)
							(end -0.1778 0.2794)
						)
						(arc
							(start 0.1778 0.2794)
							(mid 0.249642 0.249642)
							(end 0.2794 0.1778)
						)
						(arc
							(start 0.2794 -0.1778)
							(mid 0.249642 -0.249642)
							(end 0.1778 -0.2794)
						)
					)
					(width 0)
					(fill yes)
				)
			)
		)
	)
	(footprint ""
		(layer "F.Cu")
		(at 166.466012 -131.46024 90)
		(property "Reference" "R846"
			(at 0 0 90)
			(layer "F.SilkS")
			(hide yes)
			(effects
				(font
					(size 1.27 1.27)
				)
			)
		)
		(property "Value" "4K7R2F-GP"
			(at 0.064008 -3.993896 90)
			(unlocked yes)
			(layer "F.Fab")
			(hide yes)
			(effects
				(font
					(size 1.016 1.016)
					(thickness 0.1524)
				)
			)
		)
		(property "Device Type" "R402H16"
			(at 0.064008 -5.517896 90)
			(unlocked yes)
			(layer "F.Fab")
			(hide yes)
			(effects
				(font
					(size 1.016 1.016)
					(thickness 0.1524)
				)
			)
		)
		(duplicate_pad_numbers_are_jumpers no)
		(fp_line
			(start 0.508 -0.9398)
			(end -0.508 -0.9398)
			(stroke
				(width 0.1524)
				(type default)
			)
			(layer "F.SilkS")
		)
		(fp_line
			(start -0.508 -0.9398)
			(end -0.508 0.9398)
			(stroke
				(width 0.1524)
				(type default)
			)
			(layer "F.SilkS")
		)
		(fp_rect
			(start -0.508 0.9398)
			(end 0.508 -0.9398)
			(stroke
				(width 0)
				(type default)
			)
			(fill no)
			(layer "F.CrtYd")
		)
		(fp_rect
			(start -0.508 0.9398)
			(end 0.508 -0.9398)
			(stroke
				(width 0)
				(type default)
			)
			(fill no)
			(layer "F.Fab")
		)
		(pad "1" smd custom
			(at 0 -0.4445 90)
			(size 0.1397 0.1397)
			(layers "F.Cu" "F.Mask" "F.Paste")
			(net "P3V3_STBY")
			(options
				(clearance outline)
				(anchor circle)
			)
			(primitives
				(gr_poly
					(pts
						(arc
							(start -0.1778 -0.2794)
							(mid -0.249642 -0.249642)
							(end -0.2794 -0.1778)
						)
						(arc
							(start -0.2794 0.1778)
							(mid -0.249642 0.249642)
							(end -0.1778 0.2794)
						)
						(arc
							(start 0.1778 0.2794)
							(mid 0.249642 0.249642)
							(end 0.2794 0.1778)
						)
						(arc
							(start 0.2794 -0.1778)
							(mid 0.249642 -0.249642)
							(end 0.1778 -0.2794)
						)
					)
					(width 0)
					(fill yes)
				)
			)
		)
		(pad "2" smd custom
			(at 0 0.4445 90)
			(size 0.1397 0.1397)
			(layers "F.Cu" "F.Mask" "F.Paste")
			(net "M2_2_ACTIVE_N")
			(options
				(clearance outline)
				(anchor circle)
			)
			(primitives
				(gr_poly
					(pts
						(arc
							(start -0.1778 -0.2794)
							(mid -0.249642 -0.249642)
							(end -0.2794 -0.1778)
						)
						(arc
							(start -0.2794 0.1778)
							(mid -0.249642 0.249642)
							(end -0.1778 0.2794)
						)
						(arc
							(start 0.1778 0.2794)
							(mid 0.249642 0.249642)
							(end 0.2794 0.1778)
						)
						(arc
							(start 0.2794 -0.1778)
							(mid 0.249642 -0.249642)
							(end 0.1778 -0.2794)
						)
					)
					(width 0)
					(fill yes)
				)
			)
		)
	)
)
